FILE_TYPE = CONNECTIVITY;
{Allegro Design Entry HDL 17.4-2019 S026 (4007227) 1/17/2022}
"PAGE_NUMBER" = 82;
0"NC";
1"GND\g";
2"GND\g";
3"GND\g";
4"GND\g";
5"GND\g";
6"GND\g";
7"GND\g";
8"GND\g";
9"GND\g";
10"GND\g";
11"GND\g";
12"GND\g";
13"GND\g";
14"GND\g";
15"GND\g";
16"SCM_SYS_PWRBTN_N";
17"FM_APML_MUX2_SEL";
18"E1S_0_PRSNT_N";
19"P3V3_AUX\g";
20"GND\g";
21"P3V3_AUX\g";
22"GND\g";
23"P3V3_AUX\g";
24"P1V8_AUX\g";
25"PVDD18_S5_P0\g";
26"PVDD18_S5_P1\g";
27"GND\g";
28"P1V8_AUX\g";
29"RST_PERST_E1S_0_N";
30"RST_PERST_M2_0_N";
31"P12V_OCP_SFF_EN_R";
32"FM_I3C_CPU1_MUX0_OE_N";
33"PVDDCR_CPU0_P1_PMALERT";
34"PVDDCR_CPU0_P0_PMALERT";
35"PVDDCR_CPU1_P1_SMB_ALERT";
36"PVDDCR_CPU1_P0_SMB_ALERT";
37"PVDD11_S3_P1_PMALERT";
38"PVDD11_S3_P0_PMALERT";
39"PRSNT_HDT_N";
40"FM_SYS_THROTTLE_N"CDS_PHYS_NET_NAME"FM_SYS_THROTTLE_N";
41"CPLD_JTAG_EN";
42"CPLD_PROGRAMN";
43"E1S_0_P12V_EN";
44"FM_SEC_MUX_SEL";
45"FM_APML_MUX2_OE_N";
46"P12V_OCP_V3_2_EN_R";
47"P3V3_OCP_V3_2_EN_R";
48"FM_SEC_MUX_OE_N";
49"SCM_USB_OC_N";
50"FM_P1_PCC0_N";
51"FM_P1_PCC1_N";
52"P3V3_OCP_SFF_EN_R";
53"E1S_0_P3V3_EN";
54"RST_CPU0_PERST1_N";
55"RST_CPU1_PERST1_N";
56"RST_CPU1_PERST0_N";
57"FM_APML_MUX2_SEL";
58"RST_CPU0_PERST0_N";
59"FM_I3C_CPU1_MUX1_OE_N";
60"FM_I3C_CPU0_MUX0_OE_N";
61"FM_I3C_CPU0_MUX1_OE_N";
62"FM_SEC_MUX_OE_N";
63"FM_SEC_MUX_SEL";
64"FM_P0_PCC0_N";
65"FM_P0_PCC1_N";
66"RST_CPU0_KBRST_R_N";
67"RST_PERST_CPU0_SWB_N";
68"RST_PERST_CPU1_SWB_N";
69"RST_PERST_CPU1_SWB_1_N";
70"FM_ESPI_CPU0_ALERT_R_SEL";
71"FM_APML_MUX2_OE_N";
%"Q_CAP"
"2","(-1200,525)","0","pure_quanta","I102";
;
LOCATION"C362"
$SEC"1"
CDS_SEC"1"
VALUE"0.1UF"
PACK_TYPE"C0402"
VOLTAGE"16V"
TOLERANCE"10%"
MATERIAL"X7R"
CDS_LIB"pure_quanta"
PART_NUMBER"CH4103K1B08";
"A"
$PN"1"21;
"B"
$PN"2"20;
%"Q_CAP"
"2","(-1200,725)","0","pure_quanta","I103";
;
LOCATION"C360"
$SEC"1"
CDS_SEC"1"
VALUE"0.1UF"
PACK_TYPE"C0402"
VOLTAGE"16V"
TOLERANCE"10%"
MATERIAL"X7R"
CDS_LIB"pure_quanta"
PART_NUMBER"CH4103K1B08";
"A"
$PN"1"21;
"B"
$PN"2"20;
%"Q_CAP"
"2","(-1200,625)","0","pure_quanta","I104";
;
LOCATION"C361"
$SEC"1"
CDS_SEC"1"
VALUE"0.1UF"
PACK_TYPE"C0402"
VOLTAGE"16V"
TOLERANCE"10%"
MATERIAL"X7R"
CDS_LIB"pure_quanta"
PART_NUMBER"CH4103K1B08";
"A"
$PN"1"21;
"B"
$PN"2"20;
%"Q_CAP"
"2","(-1200,925)","0","pure_quanta","I105";
;
LOCATION"C358"
$SEC"1"
CDS_SEC"1"
VALUE"0.1UF"
PACK_TYPE"C0402"
VOLTAGE"16V"
TOLERANCE"10%"
MATERIAL"X7R"
CDS_LIB"pure_quanta"
PART_NUMBER"CH4103K1B08";
"A"
$PN"1"21;
"B"
$PN"2"20;
%"Q_CAP"
"2","(-1200,1025)","0","pure_quanta","I106";
;
LOCATION"C357"
$SEC"1"
CDS_SEC"1"
VALUE"0.1UF"
PACK_TYPE"C0402"
VOLTAGE"16V"
TOLERANCE"10%"
MATERIAL"X7R"
CDS_LIB"pure_quanta"
PART_NUMBER"CH4103K1B08";
"A"
$PN"1"21;
"B"
$PN"2"20;
%"Q_CAP"
"2","(-1200,1125)","0","pure_quanta","I107";
;
LOCATION"C356"
$SEC"1"
CDS_SEC"1"
VALUE"0.1UF"
PACK_TYPE"C0402"
VOLTAGE"16V"
TOLERANCE"10%"
MATERIAL"X7R"
CDS_LIB"pure_quanta"
PART_NUMBER"CH4103K1B08";
"A"
$PN"1"21;
"B"
$PN"2"20;
%"Q_CAP"
"2","(-1200,1225)","0","pure_quanta","I108";
;
LOCATION"C355"
$SEC"1"
CDS_SEC"1"
VALUE"0.1UF"
PACK_TYPE"C0402"
VOLTAGE"16V"
TOLERANCE"10%"
MATERIAL"X7R"
CDS_LIB"pure_quanta"
PART_NUMBER"CH4103K1B08";
"A"
$PN"1"21;
"B"
$PN"2"20;
%"Q_CAP"
"2","(-1200,1325)","0","pure_quanta","I109";
;
LOCATION"C1176"
$SEC"1"
CDS_SEC"1"
VALUE"0.1UF"
PACK_TYPE"C0402"
VOLTAGE"16V"
TOLERANCE"10%"
MATERIAL"X7R"
CDS_LIB"pure_quanta"
PART_NUMBER"CH4103K1B08";
"A"
$PN"1"21;
"B"
$PN"2"20;
%"Q_CAP"
"2","(-1200,1425)","0","pure_quanta","I110";
;
LOCATION"C1175"
$SEC"1"
CDS_SEC"1"
VALUE"0.1UF"
PACK_TYPE"C0402"
VOLTAGE"16V"
TOLERANCE"10%"
MATERIAL"X7R"
CDS_LIB"pure_quanta"
PART_NUMBER"CH4103K1B08";
"A"
$PN"1"21;
"B"
$PN"2"20;
%"Q_CAP"
"2","(-1200,1525)","0","pure_quanta","I111";
;
LOCATION"C1174"
$SEC"1"
CDS_SEC"1"
VALUE"0.1UF"
PACK_TYPE"C0402"
VOLTAGE"16V"
TOLERANCE"10%"
MATERIAL"X7R"
CDS_LIB"pure_quanta"
PART_NUMBER"CH4103K1B08";
"A"
$PN"1"21;
"B"
$PN"2"20;
%"Q_CAP"
"2","(-1200,1725)","0","pure_quanta","I112";
;
LOCATION"C1172"
$SEC"1"
CDS_SEC"1"
VALUE"0.1UF"
PACK_TYPE"C0402"
VOLTAGE"16V"
TOLERANCE"10%"
MATERIAL"X7R"
CDS_LIB"pure_quanta"
PART_NUMBER"CH4103K1B08";
"A"
$PN"1"21;
"B"
$PN"2"20;
%"Q_CAP"
"2","(-1200,1625)","0","pure_quanta","I113";
;
LOCATION"C1173"
$SEC"1"
CDS_SEC"1"
VALUE"0.1UF"
PACK_TYPE"C0402"
VOLTAGE"16V"
TOLERANCE"10%"
MATERIAL"X7R"
CDS_LIB"pure_quanta"
PART_NUMBER"CH4103K1B08";
"A"
$PN"1"21;
"B"
$PN"2"20;
%"Q_CAP"
"2","(-1200,1825)","0","pure_quanta","I114";
;
LOCATION"C1171"
$SEC"1"
CDS_SEC"1"
PACK_TYPE"C0402"
VOLTAGE"16V"
VALUE"0.1UF"
TOLERANCE"10%"
MATERIAL"X7R"
CDS_LIB"pure_quanta"
PART_NUMBER"CH4103K1B08";
"A"
$PN"1"21;
"B"
$PN"2"20;
%"GND"
"1","(-375,475)","0","pure_quanta_power","I115";
;
CDS_LIB"pure_quanta_power"
BOM_COST"MEM"
SIZE"1B"
HDL_POWER"GND";
"A<SIZE-1..0>\NAC"20;
%"VCC_CORE"
"1","(-1575,2150)","0","pure_quanta_power","I116";
;
HDL_POWER"P3V3_AUX"
CDS_LIB"pure_quanta_power";
"A"21;
%"GND"
"1","(-3625,4250)","0","pure_quanta_power","I117";
;
CDS_LIB"pure_quanta_power"
SIZE"1B"
BOM_COST"MEM"
HDL_POWER"GND";
"A<SIZE-1..0>\NAC"1;
%"Q_RES"
"2","(-3625,4475)","0","pure_quanta","I118";
;
LOCATION"R800"
$SEC"1"
CDS_SEC"1"
VALUE"10K"
MATERIAL"CHIP"
WATTAGE"1/16W"
TOLERANCE"1%"
PACK_TYPE"0402LF"
CDS_LIB"pure_quanta"
BOM_COST"MEM"
PART_NUMBER"CS31002FB08";
"A"
$PN"1"29;
"B"
$PN"2"1;
%"GND"
"1","(-3425,4250)","0","mstr_symbols","I119";
;
VOLTAGE"0.0"
CDS_LIB"mstr_symbols"
SIZE"1B"
BOM_COST"MEM"
BODY_TYPE"PLUMBING"
HDL_POWER"GND";
"A\NAC"2;
%"Q_RES"
"2","(-3425,4475)","0","pure_quanta","I120";
;
LOCATION"R804"
$SEC"1"
CDS_SEC"1"
WATTAGE"1/16W"
MATERIAL"CHIP"
TOLERANCE"1%"
VALUE"10K"
PACK_TYPE"0402LF"
CDS_LIB"pure_quanta"
BOM_COST"MEM"
PART_NUMBER"CS31002FB08";
"A"
$PN"1"30;
"B"
$PN"2"2;
%"GND"
"1","(-3500,5575)","0","pure_quanta_power","I121";
;
BOM_COST"MEM"
SIZE"1B"
CDS_LIB"pure_quanta_power"
HDL_POWER"GND";
"A<SIZE-1..0>\NAC"3;
%"GND"
"1","(-3300,5575)","0","pure_quanta_power","I122";
;
BOM_COST"MEM"
SIZE"1B"
CDS_LIB"pure_quanta_power"
HDL_POWER"GND";
"A<SIZE-1..0>\NAC"4;
%"GND"
"1","(-3100,5575)","0","mstr_symbols","I123";
;
VOLTAGE"0.0"
SIZE"1B"
BOM_COST"MEM"
CDS_LIB"mstr_symbols"
BODY_TYPE"PLUMBING"
HDL_POWER"GND";
"A\NAC"5;
%"Q_RES"
"2","(-3500,5800)","0","pure_quanta","I124";
;
LOCATION"R16"
$SEC"1"
CDS_SEC"1"
TOLERANCE"1%"
VALUE"10K"
PACK_TYPE"0402LF"
MATERIAL"CHIP"
WATTAGE"1/16W"
BOM_COST"MEM"
CDS_LIB"pure_quanta"
PART_NUMBER"CS31002FB08";
"A"
$PN"1"58;
"B"
$PN"2"3;
%"Q_RES"
"2","(-3300,5800)","0","pure_quanta","I125";
;
LOCATION"R17"
$SEC"1"
CDS_SEC"1"
TOLERANCE"1%"
VALUE"10K"
PACK_TYPE"0402LF"
MATERIAL"CHIP"
WATTAGE"1/16W"
BOM_COST"MEM"
CDS_LIB"pure_quanta"
PART_NUMBER"CS31002FB08";
"A"
$PN"1"54;
"B"
$PN"2"4;
%"Q_RES"
"2","(-3100,5800)","0","pure_quanta","I126";
;
LOCATION"R18"
$SEC"1"
CDS_SEC"1"
MATERIAL"CHIP"
TOLERANCE"1%"
VALUE"10K"
PACK_TYPE"0402LF"
WATTAGE"1/16W"
BOM_COST"MEM"
CDS_LIB"pure_quanta"
PART_NUMBER"CS31002FB08";
"A"
$PN"1"56;
"B"
$PN"2"5;
%"GND"
"1","(-2875,5575)","0","mstr_symbols","I127";
;
VOLTAGE"0.0"
CDS_LIB"mstr_symbols"
SIZE"1B"
BOM_COST"MEM"
BODY_TYPE"PLUMBING"
HDL_POWER"GND";
"A\NAC"6;
%"Q_RES"
"2","(-2875,5800)","0","pure_quanta","I128";
;
LOCATION"R19"
$SEC"1"
CDS_SEC"1"
MATERIAL"CHIP"
TOLERANCE"1%"
VALUE"10K"
PACK_TYPE"0402LF"
WATTAGE"1/16W"
CDS_LIB"pure_quanta"
BOM_COST"MEM"
PART_NUMBER"CS31002FB08";
"A"
$PN"1"55;
"B"
$PN"2"6;
%"Q_CAP"
"2","(-1200,825)","0","pure_quanta","I135";
;
LOCATION"C359"
$SEC"1"
CDS_SEC"1"
VALUE"0.1UF"
PACK_TYPE"C0402"
VOLTAGE"16V"
TOLERANCE"10%"
MATERIAL"X7R"
CDS_LIB"pure_quanta"
PART_NUMBER"CH4103K1B08";
"A"
$PN"1"21;
"B"
$PN"2"20;
%"Q_RES"
"1","(-5350,5075)","0","pure_quanta","I137";
;
LOCATION"R6114"
$SEC"1"
CDS_SEC"1"
WATTAGE"1/16W"
VALUE"2K"
MATERIAL"CHIP"
PACK_TYPE"0402LF"
TOLERANCE"1%"
CDS_LIB"pure_quanta"
PART_NUMBER"CS22002FB07";
"B"
$PN"2"22;
"A"
$PN"1"67;
%"UNIVERSAL_GND"
"1","(-4650,4775)","0","pure_quanta_power","I140";
;
CDS_LIB"pure_quanta_power"
HDL_POWER"GND";
"A"22;
%"Q_RES"
"1","(-5350,5025)","0","pure_quanta","I141";
;
LOCATION"R6115"
$SEC"1"
CDS_SEC"1"
MATERIAL"CHIP"
VALUE"2K"
PACK_TYPE"0402LF"
WATTAGE"1/16W"
TOLERANCE"1%"
CDS_LIB"pure_quanta"
PART_NUMBER"CS22002FB07";
"B"
$PN"2"22;
"A"
$PN"1"68;
%"Q_RES"
"2","(-2875,3250)","0","pure_quanta","I143";
;
LOCATION"R6185"
$SEC"1"
CDS_SEC"1"
TOLERANCE"1%"
VALUE"10K"
WATTAGE"1/16W"
MATERIAL"CHIP"
PACK_TYPE"0402LF"
BOM_COST"MEM"
CDS_LIB"pure_quanta"
PART_NUMBER"CS31002FB08";
"A"
$PN"1"62;
"B"
$PN"2"7;
%"GND"
"1","(-2875,3000)","0","pure_quanta_power","I144";
;
CDS_LIB"pure_quanta_power"
BOM_COST"MEM"
SIZE"1B"
HDL_POWER"GND";
"A<SIZE-1..0>\NAC"7;
%"Q_RES"
"1","(-7050,5175)","0","pure_quanta","I146";
;
LOCATION"R6186"
$SEC"1"
CDS_SEC"1"
MATERIAL"EMPTY"
VALUE"4.7K"
WATTAGE"1/16W"
TOLERANCE"5%"
PACK_TYPE"0402LF"
CDS_LIB"pure_quanta"
PART_NUMBER"CS24702JB10";
"B"
$PN"2"19;
"A"
$PN"1"48;
%"GND"
"1","(-2675,2975)","0","pure_quanta_power","I150";
;
CDS_LIB"pure_quanta_power"
BOM_COST"MEM"
SIZE"1B"
HDL_POWER"GND";
"A<SIZE-1..0>\NAC"8;
%"Q_RES"
"2","(-2675,3225)","0","pure_quanta","I151";
;
LOCATION"R6187"
$SEC"1"
CDS_SEC"1"
PACK_TYPE"0402LF"
WATTAGE"1/16W"
MATERIAL"EMPTY"
TOLERANCE"1%"
VALUE"10K"
CDS_LIB"pure_quanta"
PART_NUMBER"CS31002FB08";
"A"
$PN"1"63;
"B"
$PN"2"8;
%"Q_RES"
"1","(-7050,5125)","0","pure_quanta","I152";
;
LOCATION"R6188"
$SEC"1"
CDS_SEC"1"
MATERIAL"EMPTY"
VALUE"4.7K"
PACK_TYPE"0402LF"
TOLERANCE"5%"
WATTAGE"1/16W"
CDS_LIB"pure_quanta"
PART_NUMBER"CS24702JB10";
"B"
$PN"2"19;
"A"
$PN"1"44;
%"Q_RES"
"1","(-5350,4925)","0","pure_quanta","I154";
;
LOCATION"R3"
$SEC"1"
CDS_SEC"1"
VALUE"2K"
MATERIAL"CHIP"
CDS_LIB"pure_quanta"
TOLERANCE"1%"
WATTAGE"1/16W"
PACK_TYPE"0402LF"
PART_NUMBER"CS22002FB07";
"B"
$PN"2"22;
"A"
$PN"1"69;
%"Q_RES"
"1","(-7050,4925)","0","pure_quanta","I156";
;
LOCATION"R134"
$SEC"1"
CDS_SEC"1"
MATERIAL"EMPTY"
VALUE"4.7K"
WATTAGE"1/16W"
TOLERANCE"5%"
PACK_TYPE"0402LF"
CDS_LIB"pure_quanta"
PART_NUMBER"CS24702JB10";
"B"
$PN"2"19;
"A"
$PN"1"45;
%"Q_RES"
"1","(-7050,4875)","0","pure_quanta","I157";
;
LOCATION"R135"
$SEC"1"
CDS_SEC"1"
VALUE"4.7K"
MATERIAL"EMPTY"
PACK_TYPE"0402LF"
TOLERANCE"5%"
WATTAGE"1/16W"
CDS_LIB"pure_quanta"
PART_NUMBER"CS24702JB10";
"B"
$PN"2"19;
"A"
$PN"1"17;
%"Q_RES"
"2","(-4050,3250)","0","pure_quanta","I162";
;
LOCATION"R136"
$SEC"1"
CDS_SEC"1"
MATERIAL"EMPTY"
PACK_TYPE"0402LF"
WATTAGE"1/16W"
VALUE"10K"
TOLERANCE"1%"
CDS_LIB"pure_quanta"
PART_NUMBER"CS31002FB08";
"A"
$PN"1"57;
"B"
$PN"2"9;
%"Q_RES"
"2","(-4250,3250)","0","pure_quanta","I163";
;
LOCATION"R126"
$SEC"1"
CDS_SEC"1"
VALUE"10K"
TOLERANCE"1%"
WATTAGE"1/16W"
MATERIAL"CHIP"
PACK_TYPE"0402LF"
CDS_LIB"pure_quanta"
BOM_COST"MEM"
PART_NUMBER"CS31002FB08";
"A"
$PN"1"71;
"B"
$PN"2"10;
%"GND"
"1","(-4050,3000)","0","pure_quanta_power","I164";
;
CDS_LIB"pure_quanta_power"
SIZE"1B"
BOM_COST"MEM"
HDL_POWER"GND";
"A<SIZE-1..0>\NAC"9;
%"GND"
"1","(-4250,3000)","0","pure_quanta_power","I165";
;
SIZE"1B"
BOM_COST"MEM"
CDS_LIB"pure_quanta_power"
HDL_POWER"GND";
"A<SIZE-1..0>\NAC"10;
%"Q_RES"
"1","(-7075,3000)","0","pure_quanta","I166";
;
LOCATION"R64"
$SEC"1"
CDS_SEC"1"
MATERIAL"EMPTY"
VALUE"1K"
TOLERANCE"1%"
PACK_TYPE"0402LF"
WATTAGE"1/16W"
CDS_LIB"pure_quanta"
PART_NUMBER"CS21002FB06";
"B"
$PN"2"23;
"A"
$PN"1"16;
%"GND"
"1","(-4475,3000)","0","pure_quanta_power","I169";
;
CDS_LIB"pure_quanta_power"
SIZE"1B"
BOM_COST"MEM"
HDL_POWER"GND";
"A<SIZE-1..0>\NAC"11;
%"Q_RES"
"2","(-4475,3275)","0","pure_quanta","I170";
;
LOCATION"R8033"
$SEC"1"
CDS_SEC"1"
WATTAGE"1/16W"
PACK_TYPE"0402LF"
MATERIAL"CHIP"
TOLERANCE"1%"
VALUE"1K"
CDS_LIB"pure_quanta"
PART_NUMBER"CS21002FB06";
"A"
$PN"1"70;
"B"
$PN"2"11;
%"Q_RES"
"1","(-7050,4575)","0","pure_quanta","I171";
;
LOCATION"R1304"
$SEC"1"
CDS_SEC"1"
VALUE"10K"
CDS_LIB"pure_quanta"
PACK_TYPE"0402LF"
MATERIAL"CHIP"
WATTAGE"1/16W"
TOLERANCE"1%"
PART_NUMBER"CS31002FB08";
"B"
$PN"2"19;
"A"
$PN"1"18;
%"Q_RES"
"1","(-7075,3075)","0","pure_quanta","I33";
;
LOCATION"R639"
$SEC"1"
CDS_SEC"1"
VALUE"1K"
TOLERANCE"1%"
CDS_LIB"pure_quanta"
WATTAGE"1/16W"
MATERIAL"CHIP"
PACK_TYPE"0402LF"
PART_NUMBER"CS21002FB06";
"B"
$PN"2"23;
"A"
$PN"1"42;
%"Q_RES"
"1","(-7075,3125)","0","pure_quanta","I35";
;
LOCATION"R638"
$SEC"1"
CDS_SEC"1"
VALUE"1K"
TOLERANCE"1%"
CDS_LIB"pure_quanta"
WATTAGE"1/16W"
MATERIAL"CHIP"
PACK_TYPE"0402LF"
PART_NUMBER"CS21002FB06";
"B"
$PN"2"23;
"A"
$PN"1"41;
%"Q_RES"
"1","(-7050,3600)","0","pure_quanta","I36";
;
LOCATION"R1195"
$SEC"1"
CDS_SEC"1"
VALUE"4.7K"
MATERIAL"EMPTY"
PACK_TYPE"0402LF"
TOLERANCE"5%"
WATTAGE"1/16W"
CDS_LIB"pure_quanta"
PART_NUMBER"CS24702JB10";
"B"
$PN"2"19;
"A"
$PN"1"31;
%"UNIVERSAL_POWER"
"1","(-6800,3325)","2","pure_quanta_power","I37";
;
HDL_POWER"P3V3_AUX"
CDS_LIB"pure_quanta_power";
"A"23;
%"Q_RES"
"1","(-7050,3650)","0","pure_quanta","I38";
;
LOCATION"R1071"
$SEC"1"
CDS_SEC"1"
VALUE"4.7K"
MATERIAL"EMPTY"
PACK_TYPE"0402LF"
TOLERANCE"5%"
WATTAGE"1/16W"
CDS_LIB"pure_quanta"
PART_NUMBER"CS24702JB10";
"B"
$PN"2"19;
"A"
$PN"1"52;
%"Q_RES"
"1","(-7050,3825)","0","pure_quanta","I39";
;
LOCATION"R6061"
$SEC"1"
CDS_SEC"1"
MATERIAL"EMPTY"
VALUE"4.7K"
CDS_LIB"pure_quanta"
WATTAGE"1/16W"
TOLERANCE"5%"
PACK_TYPE"0402LF"
PART_NUMBER"CS24702JB10";
"B"
$PN"2"19;
"A"
$PN"1"46;
%"Q_RES"
"1","(-7050,3775)","0","pure_quanta","I40";
;
LOCATION"R6062"
$SEC"1"
CDS_SEC"1"
MATERIAL"EMPTY"
VALUE"4.7K"
CDS_LIB"pure_quanta"
WATTAGE"1/16W"
TOLERANCE"5%"
PACK_TYPE"0402LF"
PART_NUMBER"CS24702JB10";
"B"
$PN"2"19;
"A"
$PN"1"47;
%"Q_RES"
"1","(-7050,3950)","0","pure_quanta","I41";
;
LOCATION"R757"
$SEC"1"
CDS_SEC"1"
MATERIAL"EMPTY"
VALUE"4.7K"
CDS_LIB"pure_quanta"
WATTAGE"1/16W"
TOLERANCE"5%"
PACK_TYPE"0402LF"
PART_NUMBER"CS24702JB10";
"B"
$PN"2"19;
"A"
$PN"1"53;
%"Q_RES"
"1","(-7050,4325)","0","pure_quanta","I53";
;
LOCATION"R993"
$SEC"1"
CDS_SEC"1"
VALUE"1K"
TOLERANCE"1%"
CDS_LIB"pure_quanta"
WATTAGE"1/16W"
MATERIAL"CHIP"
PACK_TYPE"0402LF"
PART_NUMBER"CS21002FB06";
"B"
$PN"2"19;
"A"
$PN"1"40;
%"Q_RES"
"1","(-7050,4200)","0","pure_quanta","I54";
;
LOCATION"R1314"
$SEC"1"
CDS_SEC"1"
VALUE"4.7K"
MATERIAL"EMPTY"
CDS_LIB"pure_quanta"
PACK_TYPE"0402LF"
TOLERANCE"5%"
WATTAGE"1/16W"
PART_NUMBER"CS24702JB10";
"B"
$PN"2"19;
"A"
$PN"1"43;
%"Q_RES"
"1","(-7050,5250)","0","pure_quanta","I56";
;
LOCATION"R1527"
$SEC"1"
CDS_SEC"1"
VALUE"1K"
TOLERANCE"1%"
CDS_LIB"pure_quanta"
WATTAGE"1/16W"
MATERIAL"CHIP"
PACK_TYPE"0402LF"
PART_NUMBER"CS21002FB06";
"B"
$PN"2"19;
"A"
$PN"1"39;
%"Q_RES"
"1","(-7050,5375)","0","pure_quanta","I57";
;
LOCATION"R1189"
$SEC"1"
CDS_SEC"1"
VALUE"1K"
TOLERANCE"1%"
CDS_LIB"pure_quanta"
WATTAGE"1/16W"
MATERIAL"CHIP"
PACK_TYPE"0402LF"
PART_NUMBER"CS21002FB06";
"B"
$PN"2"19;
"A"
$PN"1"38;
%"Q_RES"
"1","(-7050,5325)","0","pure_quanta","I58";
;
LOCATION"R1190"
$SEC"1"
CDS_SEC"1"
VALUE"1K"
TOLERANCE"1%"
CDS_LIB"pure_quanta"
WATTAGE"1/16W"
MATERIAL"CHIP"
PACK_TYPE"0402LF"
PART_NUMBER"CS21002FB06";
"B"
$PN"2"19;
"A"
$PN"1"37;
%"Q_RES"
"1","(-7050,5475)","0","pure_quanta","I59";
;
LOCATION"R1187"
$SEC"1"
CDS_SEC"1"
VALUE"1K"
TOLERANCE"1%"
CDS_LIB"pure_quanta"
WATTAGE"1/16W"
MATERIAL"CHIP"
PACK_TYPE"0402LF"
PART_NUMBER"CS21002FB06";
"B"
$PN"2"19;
"A"
$PN"1"33;
%"Q_RES"
"1","(-7050,5525)","0","pure_quanta","I60";
;
LOCATION"R1186"
$SEC"1"
CDS_SEC"1"
VALUE"1K"
TOLERANCE"1%"
CDS_LIB"pure_quanta"
WATTAGE"1/16W"
MATERIAL"CHIP"
PACK_TYPE"0402LF"
PART_NUMBER"CS21002FB06";
"B"
$PN"2"19;
"A"
$PN"1"36;
%"Q_RES"
"1","(-7050,5425)","0","pure_quanta","I61";
;
LOCATION"R1188"
$SEC"1"
CDS_SEC"1"
VALUE"1K"
TOLERANCE"1%"
CDS_LIB"pure_quanta"
WATTAGE"1/16W"
MATERIAL"CHIP"
PACK_TYPE"0402LF"
PART_NUMBER"CS21002FB06";
"B"
$PN"2"19;
"A"
$PN"1"35;
%"Q_RES"
"1","(-7050,5575)","0","pure_quanta","I62";
;
LOCATION"R1185"
$SEC"1"
CDS_SEC"1"
VALUE"1K"
TOLERANCE"1%"
CDS_LIB"pure_quanta"
WATTAGE"1/16W"
MATERIAL"CHIP"
PACK_TYPE"0402LF"
PART_NUMBER"CS21002FB06";
"B"
$PN"2"19;
"A"
$PN"1"34;
%"VCC_CORE"
"1","(-6800,5650)","0","pure_quanta_power","I63";
;
HDL_POWER"P3V3_AUX"
CDS_LIB"pure_quanta_power";
"A"19;
%"Q_RES"
"1","(-7050,5750)","0","pure_quanta","I64";
;
LOCATION"R654"
$SEC"1"
CDS_SEC"1"
VALUE"4.7K"
PACK_TYPE"0402LF"
CDS_LIB"pure_quanta"
WATTAGE"1/16W"
MATERIAL"CHIP"
TOLERANCE"5%"
PART_NUMBER"CS24702JB10";
"B"
$PN"2"24;
"A"
$PN"1"49;
%"VCC_CORE"
"1","(-6825,6375)","0","pure_quanta_power","I70";
;
HDL_POWER"P1V8_AUX"
CDS_LIB"pure_quanta_power";
"A"24;
%"Q_RES"
"1","(-4925,5275)","0","pure_quanta","I72";
;
LOCATION"R1351"
$SEC"1"
CDS_SEC"1"
VALUE"2.2K"
PACK_TYPE"0402LF"
TOLERANCE"5%"
MATERIAL"CHIP"
WATTAGE"1/16W"
CDS_LIB"pure_quanta"
PART_NUMBER"CS22202JB07";
"B"
$PN"2"25;
"A"
$PN"1"66;
%"Q_RES"
"1","(-4925,5350)","0","pure_quanta","I73";
;
LOCATION"R1288"
$SEC"1"
CDS_SEC"1"
VALUE"4.7K"
CDS_LIB"pure_quanta"
WATTAGE"1/16W"
MATERIAL"CHIP"
TOLERANCE"5%"
PACK_TYPE"0402LF"
PART_NUMBER"CS24702JB10";
"B"
$PN"2"25;
"A"
$PN"1"65;
%"Q_RES"
"1","(-4925,5400)","0","pure_quanta","I74";
;
LOCATION"R1287"
$SEC"1"
CDS_SEC"1"
VALUE"4.7K"
CDS_LIB"pure_quanta"
WATTAGE"1/16W"
MATERIAL"CHIP"
TOLERANCE"5%"
PACK_TYPE"0402LF"
PART_NUMBER"CS24702JB10";
"B"
$PN"2"25;
"A"
$PN"1"64;
%"VCC_CORE"
"1","(-4650,5550)","0","pure_quanta_power","I75";
;
HDL_POWER"PVDD18_S5_P0"
CDS_LIB"pure_quanta_power";
"A"25;
%"Q_RES"
"1","(-4925,5850)","0","pure_quanta","I76";
;
LOCATION"R1286"
$SEC"1"
CDS_SEC"1"
VALUE"4.7K"
CDS_LIB"pure_quanta"
WATTAGE"1/16W"
MATERIAL"CHIP"
TOLERANCE"5%"
PACK_TYPE"0402LF"
PART_NUMBER"CS24702JB10";
"B"
$PN"2"26;
"A"
$PN"1"51;
%"Q_RES"
"1","(-4925,5900)","0","pure_quanta","I77";
;
LOCATION"R1285"
$SEC"1"
CDS_SEC"1"
VALUE"4.7K"
CDS_LIB"pure_quanta"
WATTAGE"1/16W"
MATERIAL"CHIP"
TOLERANCE"5%"
PACK_TYPE"0402LF"
PART_NUMBER"CS24702JB10";
"B"
$PN"2"26;
"A"
$PN"1"50;
%"VCC_CORE"
"1","(-4650,6025)","0","pure_quanta_power","I78";
;
HDL_POWER"PVDD18_S5_P1"
CDS_LIB"pure_quanta_power";
"A"26;
%"Q_CAP"
"2","(-3450,1075)","0","pure_quanta","I79";
;
LOCATION"C1134"
$SEC"1"
CDS_SEC"1"
VALUE"0.1UF"
PACK_TYPE"C0402"
VOLTAGE"16V"
TOLERANCE"10%"
MATERIAL"X7R"
CDS_LIB"pure_quanta"
PART_NUMBER"CH4103K1B08";
"A"
$PN"1"28;
"B"
$PN"2"27;
%"Q_CAP"
"2","(-3450,1275)","0","pure_quanta","I80";
;
LOCATION"C1132"
$SEC"1"
CDS_SEC"1"
VALUE"0.1UF"
PACK_TYPE"C0402"
VOLTAGE"16V"
TOLERANCE"10%"
MATERIAL"X7R"
CDS_LIB"pure_quanta"
PART_NUMBER"CH4103K1B08";
"A"
$PN"1"28;
"B"
$PN"2"27;
%"Q_CAP"
"2","(-3450,1175)","0","pure_quanta","I81";
;
LOCATION"C1133"
$SEC"1"
CDS_SEC"1"
VALUE"0.1UF"
PACK_TYPE"C0402"
VOLTAGE"16V"
TOLERANCE"10%"
MATERIAL"X7R"
CDS_LIB"pure_quanta"
PART_NUMBER"CH4103K1B08";
"A"
$PN"1"28;
"B"
$PN"2"27;
%"Q_CAP"
"2","(-3450,1375)","0","pure_quanta","I82";
;
LOCATION"C1131"
$SEC"1"
CDS_SEC"1"
VALUE"0.1UF"
PACK_TYPE"C0402"
VOLTAGE"16V"
TOLERANCE"10%"
MATERIAL"X7R"
CDS_LIB"pure_quanta"
PART_NUMBER"CH4103K1B08";
"A"
$PN"1"28;
"B"
$PN"2"27;
%"Q_CAP"
"2","(-3450,1575)","0","pure_quanta","I83";
;
LOCATION"C352"
$SEC"1"
CDS_SEC"1"
VALUE"0.1UF"
PACK_TYPE"C0402"
VOLTAGE"16V"
TOLERANCE"10%"
MATERIAL"X7R"
CDS_LIB"pure_quanta"
PART_NUMBER"CH4103K1B08";
"A"
$PN"1"28;
"B"
$PN"2"27;
%"Q_CAP"
"2","(-3450,1775)","0","pure_quanta","I84";
;
LOCATION"C1128"
$SEC"1"
CDS_SEC"1"
VALUE"0.1UF"
PACK_TYPE"C0402"
VOLTAGE"16V"
TOLERANCE"10%"
MATERIAL"X7R"
CDS_LIB"pure_quanta"
PART_NUMBER"CH4103K1B08";
"A"
$PN"1"28;
"B"
$PN"2"27;
%"Q_CAP"
"2","(-3450,1675)","0","pure_quanta","I85";
;
LOCATION"C1129"
$SEC"1"
CDS_SEC"1"
VALUE"0.1UF"
PACK_TYPE"C0402"
VOLTAGE"16V"
TOLERANCE"10%"
MATERIAL"X7R"
CDS_LIB"pure_quanta"
PART_NUMBER"CH4103K1B08";
"A"
$PN"1"28;
"B"
$PN"2"27;
%"Q_CAP"
"2","(-3450,1975)","0","pure_quanta","I86";
;
LOCATION"C1126"
$SEC"1"
CDS_SEC"1"
MATERIAL"X7R"
VALUE"0.1UF"
TOLERANCE"10%"
VOLTAGE"16V"
PACK_TYPE"C0402"
CDS_LIB"pure_quanta"
PART_NUMBER"CH4103K1B08";
"A"
$PN"1"28;
"B"
$PN"2"27;
%"Q_CAP"
"2","(-3450,1875)","0","pure_quanta","I87";
;
LOCATION"C1127"
$SEC"1"
CDS_SEC"1"
VALUE"0.1UF"
PACK_TYPE"C0402"
VOLTAGE"16V"
TOLERANCE"10%"
MATERIAL"X7R"
CDS_LIB"pure_quanta"
PART_NUMBER"CH4103K1B08";
"A"
$PN"1"28;
"B"
$PN"2"27;
%"GND"
"1","(-2100,675)","0","pure_quanta_power","I88";
;
CDS_LIB"pure_quanta_power"
SIZE"1B"
BOM_COST"MEM"
HDL_POWER"GND";
"A<SIZE-1..0>\NAC"27;
%"VCC_CORE"
"1","(-3825,2150)","0","pure_quanta_power","I89";
;
HDL_POWER"P1V8_AUX"
CDS_LIB"pure_quanta_power";
"A"28;
%"GND"
"1","(-3700,3025)","0","pure_quanta_power","I90";
;
CDS_LIB"pure_quanta_power"
BOM_COST"MEM"
SIZE"1B"
HDL_POWER"GND";
"A<SIZE-1..0>\NAC"12;
%"GND"
"1","(-3500,3025)","0","pure_quanta_power","I91";
;
CDS_LIB"pure_quanta_power"
SIZE"1B"
BOM_COST"MEM"
HDL_POWER"GND";
"A<SIZE-1..0>\NAC"13;
%"GND"
"1","(-3300,3025)","0","pure_quanta_power","I92";
;
CDS_LIB"pure_quanta_power"
BOM_COST"MEM"
SIZE"1B"
HDL_POWER"GND";
"A<SIZE-1..0>\NAC"14;
%"Q_RES"
"2","(-3700,3250)","0","pure_quanta","I93";
;
LOCATION"R10"
$SEC"1"
CDS_SEC"1"
WATTAGE"1/16W"
PACK_TYPE"0402LF"
TOLERANCE"1%"
VALUE"10K"
MATERIAL"CHIP"
CDS_LIB"pure_quanta"
BOM_COST"MEM"
PART_NUMBER"CS31002FB08";
"A"
$PN"1"60;
"B"
$PN"2"12;
%"Q_RES"
"2","(-3500,3250)","0","pure_quanta","I94";
;
LOCATION"R11"
$SEC"1"
CDS_SEC"1"
VALUE"10K"
PACK_TYPE"0402LF"
TOLERANCE"1%"
MATERIAL"CHIP"
WATTAGE"1/16W"
CDS_LIB"pure_quanta"
BOM_COST"MEM"
PART_NUMBER"CS31002FB08";
"A"
$PN"1"61;
"B"
$PN"2"13;
%"Q_RES"
"2","(-3300,3250)","0","pure_quanta","I95";
;
LOCATION"R12"
$SEC"1"
CDS_SEC"1"
PACK_TYPE"0402LF"
WATTAGE"1/16W"
MATERIAL"CHIP"
VALUE"10K"
TOLERANCE"1%"
CDS_LIB"pure_quanta"
BOM_COST"MEM"
PART_NUMBER"CS31002FB08";
"A"
$PN"1"32;
"B"
$PN"2"14;
%"GND"
"1","(-3075,3025)","0","pure_quanta_power","I96";
;
CDS_LIB"pure_quanta_power"
SIZE"1B"
BOM_COST"MEM"
HDL_POWER"GND";
"A<SIZE-1..0>\NAC"15;
%"Q_RES"
"2","(-3075,3250)","0","pure_quanta","I97";
;
LOCATION"R25"
$SEC"1"
CDS_SEC"1"
PACK_TYPE"0402LF"
WATTAGE"1/16W"
TOLERANCE"1%"
MATERIAL"CHIP"
VALUE"10K"
BOM_COST"MEM"
CDS_LIB"pure_quanta"
PART_NUMBER"CS31002FB08";
"A"
$PN"1"59;
"B"
$PN"2"15;
END.
